(kicad_pcb
	(version 20260206)
	(generator "pcbnew")
	(generator_version "10.0")
	(general
		(thickness 1.6)
		(legacy_teardrops no)
	)
	(paper "A4")
	(title_block
		(title "peb — Lightning_PEB_BRD.brd")
		(comment 1 "Lightning (Wiwynn / Facebook NVMe JBOF) / footprints 1244-1250 of 2563")
	)
	(layers
		(0 "F.Cu" signal "TOP")
		(4 "In1.Cu" signal "L2GND")
		(6 "In2.Cu" signal "L3")
		(8 "In3.Cu" signal "L4VCC")
		(10 "In4.Cu" signal "L5VCC")
		(12 "In5.Cu" signal "L6")
		(14 "In6.Cu" signal "L7GND")
		(2 "B.Cu" signal "BOTTOM")
		(9 "F.Adhes" user "F.Adhesive")
		(11 "B.Adhes" user "B.Adhesive")
		(13 "F.Paste" user "Package Geometry/Pastemask Top")
		(15 "B.Paste" user "Package Geometry/Pastemask Bottom")
		(5 "F.SilkS" user "Ref Des/Silkscreen Top")
		(7 "B.SilkS" user "Ref Des/Silkscreen Bottom")
		(1 "F.Mask" user "Board Geometry/Soldermask Top")
		(3 "B.Mask" user "Board Geometry/Soldermask Bottom")
		(17 "Dwgs.User" user "User.Drawings")
		(19 "Cmts.User" user "User.Comments")
		(21 "Eco1.User" user "User.Eco1")
		(23 "Eco2.User" user "User.Eco2")
		(25 "Edge.Cuts" user "Board Geometry/Outline")
		(27 "Margin" user)
		(31 "F.CrtYd" user "Package Geometry/Place Bound Top")
		(29 "B.CrtYd" user "Package Geometry/Place Bound Bottom")
		(35 "F.Fab" user "Ref Des/Assembly Top")
		(33 "B.Fab" user "Ref Des/Assembly Bottom")
	)
	(footprint ""
		(layer "F.Cu")
		(at 194.8688 -33.909 -90)
		(property "Reference" "R763"
			(at 0 0 270)
			(layer "F.SilkS")
			(hide yes)
			(effects
				(font
					(size 1.27 1.27)
				)
			)
		)
		(property "Value" "4K7R2F-GP"
			(at 0.064008 -3.993896 270)
			(unlocked yes)
			(layer "F.Fab")
			(hide yes)
			(effects
				(font
					(size 1.016 1.016)
					(thickness 0.1524)
				)
			)
		)
		(property "Device Type" "R402H16"
			(at 0.064008 -5.517896 270)
			(unlocked yes)
			(layer "F.Fab")
			(hide yes)
			(effects
				(font
					(size 1.016 1.016)
					(thickness 0.1524)
				)
			)
		)
		(duplicate_pad_numbers_are_jumpers no)
		(fp_line
			(start -0.508 -0.9398)
			(end -0.508 0.9398)
			(stroke
				(width 0.1524)
				(type default)
			)
			(layer "F.SilkS")
		)
		(fp_line
			(start 0.508 -0.9398)
			(end -0.508 -0.9398)
			(stroke
				(width 0.1524)
				(type default)
			)
			(layer "F.SilkS")
		)
		(fp_rect
			(start -0.508 0.9398)
			(end 0.508 -0.9398)
			(stroke
				(width 0)
				(type default)
			)
			(fill no)
			(layer "F.CrtYd")
		)
		(fp_rect
			(start -0.508 0.9398)
			(end 0.508 -0.9398)
			(stroke
				(width 0)
				(type default)
			)
			(fill no)
			(layer "F.Fab")
		)
		(pad "1" smd custom
			(at 0 -0.4445 270)
			(size 0.1397 0.1397)
			(layers "F.Cu" "F.Mask" "F.Paste")
			(net "U55_A1")
			(options
				(clearance outline)
				(anchor circle)
			)
			(primitives
				(gr_poly
					(pts
						(arc
							(start -0.1778 -0.2794)
							(mid -0.249642 -0.249642)
							(end -0.2794 -0.1778)
						)
						(arc
							(start -0.2794 0.1778)
							(mid -0.249642 0.249642)
							(end -0.1778 0.2794)
						)
						(arc
							(start 0.1778 0.2794)
							(mid 0.249642 0.249642)
							(end 0.2794 0.1778)
						)
						(arc
							(start 0.2794 -0.1778)
							(mid 0.249642 -0.249642)
							(end 0.1778 -0.2794)
						)
					)
					(width 0)
					(fill yes)
				)
			)
		)
		(pad "2" smd custom
			(at 0 0.4445 270)
			(size 0.1397 0.1397)
			(layers "F.Cu" "F.Mask" "F.Paste")
			(net "P3V3_STBY")
			(options
				(clearance outline)
				(anchor circle)
			)
			(primitives
				(gr_poly
					(pts
						(arc
							(start -0.1778 -0.2794)
							(mid -0.249642 -0.249642)
							(end -0.2794 -0.1778)
						)
						(arc
							(start -0.2794 0.1778)
							(mid -0.249642 0.249642)
							(end -0.1778 0.2794)
						)
						(arc
							(start 0.1778 0.2794)
							(mid 0.249642 0.249642)
							(end 0.2794 0.1778)
						)
						(arc
							(start 0.2794 -0.1778)
							(mid 0.249642 -0.249642)
							(end 0.1778 -0.2794)
						)
					)
					(width 0)
					(fill yes)
				)
			)
		)
	)
	(footprint ""
		(layer "F.Cu")
		(at 33.6296 -184.0992)
		(property "Reference" "C262"
			(at 0 0 0)
			(layer "F.SilkS")
			(hide yes)
			(effects
				(font
					(size 1.27 1.27)
				)
			)
		)
		(property "Value" "SC220P50V3JN-GP"
			(at 0 -2.8194 0)
			(unlocked yes)
			(layer "F.Fab")
			(hide yes)
			(effects
				(font
					(size 1.016 1.016)
					(thickness 0.1524)
				)
			)
		)
		(property "Device Type" "C603H36"
			(at 0 -4.3434 0)
			(unlocked yes)
			(layer "F.Fab")
			(hide yes)
			(effects
				(font
					(size 1.016 1.016)
					(thickness 0.1524)
				)
			)
		)
		(duplicate_pad_numbers_are_jumpers no)
		(fp_line
			(start 0.508 0)
			(end -0.508 0)
			(stroke
				(width 0.2032)
				(type default)
			)
			(layer "F.SilkS")
		)
		(fp_rect
			(start -0.5842 1.3335)
			(end 0.5842 -1.3335)
			(stroke
				(width 0)
				(type default)
			)
			(fill no)
			(layer "F.CrtYd")
		)
		(fp_rect
			(start -0.5842 1.3335)
			(end 0.5842 -1.3335)
			(stroke
				(width 0)
				(type default)
			)
			(fill no)
			(layer "F.Fab")
		)
		(pad "1" smd custom
			(at 0 -0.762)
			(size 0.2159 0.2159)
			(layers "F.Cu" "F.Mask" "F.Paste")
			(net "BUF_I2C5_SDA_R")
			(options
				(clearance outline)
				(anchor circle)
			)
			(primitives
				(gr_poly
					(pts
						(arc
							(start -0.3302 -0.4318)
							(mid -0.402042 -0.402042)
							(end -0.4318 -0.3302)
						)
						(arc
							(start -0.4318 0.3302)
							(mid -0.402042 0.402042)
							(end -0.3302 0.4318)
						)
						(arc
							(start 0.3302 0.4318)
							(mid 0.402042 0.402042)
							(end 0.4318 0.3302)
						)
						(arc
							(start 0.4318 -0.3302)
							(mid 0.402042 -0.402042)
							(end 0.3302 -0.4318)
						)
					)
					(width 0)
					(fill yes)
				)
			)
		)
		(pad "2" smd custom
			(at 0 0.762)
			(size 0.2159 0.2159)
			(layers "F.Cu" "F.Mask" "F.Paste")
			(net "GND")
			(options
				(clearance outline)
				(anchor circle)
			)
			(primitives
				(gr_poly
					(pts
						(arc
							(start -0.3302 -0.4318)
							(mid -0.402042 -0.402042)
							(end -0.4318 -0.3302)
						)
						(arc
							(start -0.4318 0.3302)
							(mid -0.402042 0.402042)
							(end -0.3302 0.4318)
						)
						(arc
							(start 0.3302 0.4318)
							(mid 0.402042 0.402042)
							(end 0.4318 0.3302)
						)
						(arc
							(start 0.4318 -0.3302)
							(mid 0.402042 -0.402042)
							(end 0.3302 -0.4318)
						)
					)
					(width 0)
					(fill yes)
				)
			)
		)
	)
	(footprint ""
		(layer "F.Cu")
		(at 291.008054 -212.420454 180)
		(property "Reference" "C91"
			(at 0 0 180)
			(layer "F.SilkS")
			(hide yes)
			(effects
				(font
					(size 1.27 1.27)
				)
			)
		)
		(property "Value" "SCD22U10V2KX-1GP"
			(at 1.1811 -2.7051 180)
			(unlocked yes)
			(layer "F.Fab")
			(hide yes)
			(effects
				(font
					(size 1.016 1.016)
					(thickness 0.1524)
				)
			)
		)
		(property "Device Type" "C402H22"
			(at 1.1811 -4.2291 180)
			(unlocked yes)
			(layer "F.Fab")
			(hide yes)
			(effects
				(font
					(size 1.016 1.016)
					(thickness 0.1524)
				)
			)
		)
		(duplicate_pad_numbers_are_jumpers no)
		(fp_rect
			(start -0.4318 0.9525)
			(end 0.4318 -0.9525)
			(stroke
				(width 0)
				(type default)
			)
			(fill no)
			(layer "F.CrtYd")
		)
		(fp_rect
			(start -0.4318 0.9525)
			(end 0.4318 -0.9525)
			(stroke
				(width 0)
				(type default)
			)
			(fill no)
			(layer "F.Fab")
		)
		(pad "1" smd custom
			(at 0 -0.4445 180)
			(size 0.1524 0.1524)
			(layers "F.Cu" "F.Mask" "F.Paste")
			(net "PCIE_TX_CAP_N29")
			(options
				(clearance outline)
				(anchor circle)
			)
			(primitives
				(gr_poly
					(pts
						(arc
							(start 0.3048 -0.2032)
							(mid 0.275042 -0.275042)
							(end 0.2032 -0.3048)
						)
						(arc
							(start -0.2032 -0.3048)
							(mid -0.275042 -0.275042)
							(end -0.3048 -0.2032)
						)
						(arc
							(start -0.3048 0.2032)
							(mid -0.275042 0.275042)
							(end -0.2032 0.3048)
						)
						(arc
							(start 0.2032 0.3048)
							(mid 0.275042 0.275042)
							(end 0.3048 0.2032)
						)
					)
					(width 0)
					(fill yes)
				)
			)
		)
		(pad "2" smd custom
			(at 0 0.4445 180)
			(size 0.1524 0.1524)
			(layers "F.Cu" "F.Mask" "F.Paste")
			(net "PCIE_TX_N29")
			(options
				(clearance outline)
				(anchor circle)
			)
			(primitives
				(gr_poly
					(pts
						(arc
							(start 0.3048 -0.2032)
							(mid 0.275042 -0.275042)
							(end 0.2032 -0.3048)
						)
						(arc
							(start -0.2032 -0.3048)
							(mid -0.275042 -0.275042)
							(end -0.3048 -0.2032)
						)
						(arc
							(start -0.3048 0.2032)
							(mid -0.275042 0.275042)
							(end -0.2032 0.3048)
						)
						(arc
							(start 0.2032 0.3048)
							(mid 0.275042 0.275042)
							(end 0.3048 0.2032)
						)
					)
					(width 0)
					(fill yes)
				)
			)
		)
	)
	(footprint ""
		(layer "F.Cu")
		(at 225.909124 -190.601092)
		(property "Reference" "R7957"
			(at 0 0 0)
			(layer "F.SilkS")
			(hide yes)
			(effects
				(font
					(size 1.27 1.27)
				)
			)
		)
		(property "Value" "0R2J-2-GP"
			(at 0.064008 -3.993896 0)
			(unlocked yes)
			(layer "F.Fab")
			(hide yes)
			(effects
				(font
					(size 1.016 1.016)
					(thickness 0.1524)
				)
			)
		)
		(property "Device Type" "R402H16"
			(at 0.064008 -5.517896 0)
			(unlocked yes)
			(layer "F.Fab")
			(hide yes)
			(effects
				(font
					(size 1.016 1.016)
					(thickness 0.1524)
				)
			)
		)
		(duplicate_pad_numbers_are_jumpers no)
		(fp_line
			(start -0.508 -0.9398)
			(end -0.508 0.9398)
			(stroke
				(width 0.1524)
				(type default)
			)
			(layer "F.SilkS")
		)
		(fp_line
			(start 0.508 -0.9398)
			(end -0.508 -0.9398)
			(stroke
				(width 0.1524)
				(type default)
			)
			(layer "F.SilkS")
		)
		(fp_rect
			(start -0.508 0.9398)
			(end 0.508 -0.9398)
			(stroke
				(width 0)
				(type default)
			)
			(fill no)
			(layer "F.CrtYd")
		)
		(fp_rect
			(start -0.508 0.9398)
			(end 0.508 -0.9398)
			(stroke
				(width 0)
				(type default)
			)
			(fill no)
			(layer "F.Fab")
		)
		(pad "1" smd custom
			(at 0 -0.4445)
			(size 0.1397 0.1397)
			(layers "F.Cu" "F.Mask" "F.Paste")
			(net "SSD_PWREN8")
			(options
				(clearance outline)
				(anchor circle)
			)
			(primitives
				(gr_poly
					(pts
						(arc
							(start -0.1778 -0.2794)
							(mid -0.249642 -0.249642)
							(end -0.2794 -0.1778)
						)
						(arc
							(start -0.2794 0.1778)
							(mid -0.249642 0.249642)
							(end -0.1778 0.2794)
						)
						(arc
							(start 0.1778 0.2794)
							(mid 0.249642 0.249642)
							(end 0.2794 0.1778)
						)
						(arc
							(start 0.2794 -0.1778)
							(mid 0.249642 -0.249642)
							(end 0.1778 -0.2794)
						)
					)
					(width 0)
					(fill yes)
				)
			)
		)
		(pad "2" smd custom
			(at 0 0.4445)
			(size 0.1397 0.1397)
			(layers "F.Cu" "F.Mask" "F.Paste")
			(net "SSD_PWREN8_R")
			(options
				(clearance outline)
				(anchor circle)
			)
			(primitives
				(gr_poly
					(pts
						(arc
							(start -0.1778 -0.2794)
							(mid -0.249642 -0.249642)
							(end -0.2794 -0.1778)
						)
						(arc
							(start -0.2794 0.1778)
							(mid -0.249642 0.249642)
							(end -0.1778 0.2794)
						)
						(arc
							(start 0.1778 0.2794)
							(mid 0.249642 0.249642)
							(end 0.2794 0.1778)
						)
						(arc
							(start 0.2794 -0.1778)
							(mid 0.249642 -0.249642)
							(end 0.1778 -0.2794)
						)
					)
					(width 0)
					(fill yes)
				)
			)
		)
	)
	(footprint ""
		(layer "F.Cu")
		(at 262.919464 -8.525002 -90)
		(property "Reference" "R7905"
			(at 0 0 270)
			(layer "F.SilkS")
			(hide yes)
			(effects
				(font
					(size 1.27 1.27)
				)
			)
		)
		(property "Value" "0R2J-2-GP"
			(at 0.064008 -3.993896 270)
			(unlocked yes)
			(layer "F.Fab")
			(hide yes)
			(effects
				(font
					(size 1.016 1.016)
					(thickness 0.1524)
				)
			)
		)
		(property "Device Type" "R402H16"
			(at 0.064008 -5.517896 270)
			(unlocked yes)
			(layer "F.Fab")
			(hide yes)
			(effects
				(font
					(size 1.016 1.016)
					(thickness 0.1524)
				)
			)
		)
		(duplicate_pad_numbers_are_jumpers no)
		(fp_line
			(start -0.508 -0.9398)
			(end -0.508 0.9398)
			(stroke
				(width 0.1524)
				(type default)
			)
			(layer "F.SilkS")
		)
		(fp_line
			(start 0.508 -0.9398)
			(end -0.508 -0.9398)
			(stroke
				(width 0.1524)
				(type default)
			)
			(layer "F.SilkS")
		)
		(fp_rect
			(start -0.508 0.9398)
			(end 0.508 -0.9398)
			(stroke
				(width 0)
				(type default)
			)
			(fill no)
			(layer "F.CrtYd")
		)
		(fp_rect
			(start -0.508 0.9398)
			(end 0.508 -0.9398)
			(stroke
				(width 0)
				(type default)
			)
			(fill no)
			(layer "F.Fab")
		)
		(pad "1" smd custom
			(at 0 -0.4445 270)
			(size 0.1397 0.1397)
			(layers "F.Cu" "F.Mask" "F.Paste")
			(net "ADM6315_PM8536_RST#")
			(options
				(clearance outline)
				(anchor circle)
			)
			(primitives
				(gr_poly
					(pts
						(arc
							(start -0.1778 -0.2794)
							(mid -0.249642 -0.249642)
							(end -0.2794 -0.1778)
						)
						(arc
							(start -0.2794 0.1778)
							(mid -0.249642 0.249642)
							(end -0.1778 0.2794)
						)
						(arc
							(start 0.1778 0.2794)
							(mid 0.249642 0.249642)
							(end 0.2794 0.1778)
						)
						(arc
							(start 0.2794 -0.1778)
							(mid 0.249642 -0.249642)
							(end 0.1778 -0.2794)
						)
					)
					(width 0)
					(fill yes)
				)
			)
		)
		(pad "2" smd custom
			(at 0 0.4445 270)
			(size 0.1397 0.1397)
			(layers "F.Cu" "F.Mask" "F.Paste")
			(net "PQ21_G")
			(options
				(clearance outline)
				(anchor circle)
			)
			(primitives
				(gr_poly
					(pts
						(arc
							(start -0.1778 -0.2794)
							(mid -0.249642 -0.249642)
							(end -0.2794 -0.1778)
						)
						(arc
							(start -0.2794 0.1778)
							(mid -0.249642 0.249642)
							(end -0.1778 0.2794)
						)
						(arc
							(start 0.1778 0.2794)
							(mid 0.249642 0.249642)
							(end 0.2794 0.1778)
						)
						(arc
							(start 0.2794 -0.1778)
							(mid 0.249642 -0.249642)
							(end 0.1778 -0.2794)
						)
					)
					(width 0)
					(fill yes)
				)
			)
		)
	)
	(footprint ""
		(layer "F.Cu")
		(at 71.731124 -183.235092)
		(property "Reference" "R7935"
			(at 0 0 0)
			(layer "F.SilkS")
			(hide yes)
			(effects
				(font
					(size 1.27 1.27)
				)
			)
		)
		(property "Value" "0R2J-2-GP"
			(at 0.064008 -3.993896 0)
			(unlocked yes)
			(layer "F.Fab")
			(hide yes)
			(effects
				(font
					(size 1.016 1.016)
					(thickness 0.1524)
				)
			)
		)
		(property "Device Type" "R402H16"
			(at 0.064008 -5.517896 0)
			(unlocked yes)
			(layer "F.Fab")
			(hide yes)
			(effects
				(font
					(size 1.016 1.016)
					(thickness 0.1524)
				)
			)
		)
		(duplicate_pad_numbers_are_jumpers no)
		(fp_line
			(start -0.508 -0.9398)
			(end -0.508 0.9398)
			(stroke
				(width 0.1524)
				(type default)
			)
			(layer "F.SilkS")
		)
		(fp_line
			(start 0.508 -0.9398)
			(end -0.508 -0.9398)
			(stroke
				(width 0.1524)
				(type default)
			)
			(layer "F.SilkS")
		)
		(fp_rect
			(start -0.508 0.9398)
			(end 0.508 -0.9398)
			(stroke
				(width 0)
				(type default)
			)
			(fill no)
			(layer "F.CrtYd")
		)
		(fp_rect
			(start -0.508 0.9398)
			(end 0.508 -0.9398)
			(stroke
				(width 0)
				(type default)
			)
			(fill no)
			(layer "F.Fab")
		)
		(pad "1" smd custom
			(at 0 -0.4445)
			(size 0.1397 0.1397)
			(layers "F.Cu" "F.Mask" "F.Paste")
			(net "SSD_PRSNT#0")
			(options
				(clearance outline)
				(anchor circle)
			)
			(primitives
				(gr_poly
					(pts
						(arc
							(start -0.1778 -0.2794)
							(mid -0.249642 -0.249642)
							(end -0.2794 -0.1778)
						)
						(arc
							(start -0.2794 0.1778)
							(mid -0.249642 0.249642)
							(end -0.1778 0.2794)
						)
						(arc
							(start 0.1778 0.2794)
							(mid 0.249642 0.249642)
							(end 0.2794 0.1778)
						)
						(arc
							(start 0.2794 -0.1778)
							(mid 0.249642 -0.249642)
							(end 0.1778 -0.2794)
						)
					)
					(width 0)
					(fill yes)
				)
			)
		)
		(pad "2" smd custom
			(at 0 0.4445)
			(size 0.1397 0.1397)
			(layers "F.Cu" "F.Mask" "F.Paste")
			(net "SSD_PRSNT#0_R")
			(options
				(clearance outline)
				(anchor circle)
			)
			(primitives
				(gr_poly
					(pts
						(arc
							(start -0.1778 -0.2794)
							(mid -0.249642 -0.249642)
							(end -0.2794 -0.1778)
						)
						(arc
							(start -0.2794 0.1778)
							(mid -0.249642 0.249642)
							(end -0.1778 0.2794)
						)
						(arc
							(start 0.1778 0.2794)
							(mid 0.249642 0.249642)
							(end 0.2794 0.1778)
						)
						(arc
							(start 0.2794 -0.1778)
							(mid 0.249642 -0.249642)
							(end 0.1778 -0.2794)
						)
					)
					(width 0)
					(fill yes)
				)
			)
		)
	)
	(footprint ""
		(layer "F.Cu")
		(at 49.657 -148.59)
		(property "Reference" "R590"
			(at 0 0 0)
			(layer "F.SilkS")
			(hide yes)
			(effects
				(font
					(size 1.27 1.27)
				)
			)
		)
		(property "Value" "4K7R2F-GP"
			(at 0.064008 -3.993896 0)
			(unlocked yes)
			(layer "F.Fab")
			(hide yes)
			(effects
				(font
					(size 1.016 1.016)
					(thickness 0.1524)
				)
			)
		)
		(property "Device Type" "R402H16"
			(at 0.064008 -5.517896 0)
			(unlocked yes)
			(layer "F.Fab")
			(hide yes)
			(effects
				(font
					(size 1.016 1.016)
					(thickness 0.1524)
				)
			)
		)
		(duplicate_pad_numbers_are_jumpers no)
		(fp_line
			(start -0.508 -0.9398)
			(end -0.508 0.9398)
			(stroke
				(width 0.1524)
				(type default)
			)
			(layer "F.SilkS")
		)
		(fp_line
			(start 0.508 -0.9398)
			(end -0.508 -0.9398)
			(stroke
				(width 0.1524)
				(type default)
			)
			(layer "F.SilkS")
		)
		(fp_rect
			(start -0.508 0.9398)
			(end 0.508 -0.9398)
			(stroke
				(width 0)
				(type default)
			)
			(fill no)
			(layer "F.CrtYd")
		)
		(fp_rect
			(start -0.508 0.9398)
			(end 0.508 -0.9398)
			(stroke
				(width 0)
				(type default)
			)
			(fill no)
			(layer "F.Fab")
		)
		(pad "1" smd custom
			(at 0 -0.4445)
			(size 0.1397 0.1397)
			(layers "F.Cu" "F.Mask" "F.Paste")
			(net "TEMP_2_A0")
			(options
				(clearance outline)
				(anchor circle)
			)
			(primitives
				(gr_poly
					(pts
						(arc
							(start -0.1778 -0.2794)
							(mid -0.249642 -0.249642)
							(end -0.2794 -0.1778)
						)
						(arc
							(start -0.2794 0.1778)
							(mid -0.249642 0.249642)
							(end -0.1778 0.2794)
						)
						(arc
							(start 0.1778 0.2794)
							(mid 0.249642 0.249642)
							(end 0.2794 0.1778)
						)
						(arc
							(start 0.2794 -0.1778)
							(mid 0.249642 -0.249642)
							(end 0.1778 -0.2794)
						)
					)
					(width 0)
					(fill yes)
				)
			)
		)
		(pad "2" smd custom
			(at 0 0.4445)
			(size 0.1397 0.1397)
			(layers "F.Cu" "F.Mask" "F.Paste")
			(net "GND")
			(options
				(clearance outline)
				(anchor circle)
			)
			(primitives
				(gr_poly
					(pts
						(arc
							(start -0.1778 -0.2794)
							(mid -0.249642 -0.249642)
							(end -0.2794 -0.1778)
						)
						(arc
							(start -0.2794 0.1778)
							(mid -0.249642 0.249642)
							(end -0.1778 0.2794)
						)
						(arc
							(start 0.1778 0.2794)
							(mid 0.249642 0.249642)
							(end 0.2794 0.1778)
						)
						(arc
							(start 0.2794 -0.1778)
							(mid 0.249642 -0.249642)
							(end 0.1778 -0.2794)
						)
					)
					(width 0)
					(fill yes)
				)
			)
		)
	)
)
